(kicad_pcb
	(version 20260206)
	(generator "pcbnew")
	(generator_version "10.0")
	(general
		(thickness 1.6)
		(legacy_teardrops no)
	)
	(paper "A4")
	(title_block
		(title "01162023_DA0F0TEBIF0_F0T_Expander_BD_F_brd_V02_OCP.brd")
		(comment 1 "Grand Teton / footprint 6619 of 9728 (PEX0), pads 2236-2356 of 2397")
	)
	(layers
		(0 "F.Cu" signal "TOP")
		(4 "In1.Cu" signal "GND")
		(6 "In2.Cu" signal "VCC")
		(8 "In3.Cu" signal "VCC1")
		(10 "In4.Cu" signal "GND1")
		(12 "In5.Cu" signal "IN1")
		(14 "In6.Cu" signal "GND2")
		(16 "In7.Cu" signal "IN2")
		(18 "In8.Cu" signal "GND3")
		(20 "In9.Cu" signal "IN3")
		(22 "In10.Cu" signal "GND4")
		(24 "In11.Cu" signal "IN4")
		(26 "In12.Cu" signal "GND5")
		(28 "In13.Cu" signal "IN5")
		(30 "In14.Cu" signal "GND6")
		(32 "In15.Cu" signal "IN6")
		(34 "In16.Cu" signal "GND7")
		(2 "B.Cu" signal "BOTTOM")
		(9 "F.Adhes" user "F.Adhesive")
		(11 "B.Adhes" user "B.Adhesive")
		(13 "F.Paste" user "Package Geometry/Pastemask Top")
		(15 "B.Paste" user "Package Geometry/Pastemask Bottom")
		(5 "F.SilkS" user "Ref Des/Silkscreen Top")
		(7 "B.SilkS" user "Ref Des/Silkscreen Bottom")
		(1 "F.Mask" user "Board Geometry/Soldermask Top")
		(3 "B.Mask" user "Board Geometry/Soldermask Bottom")
		(17 "Dwgs.User" user "User.Drawings")
		(19 "Cmts.User" user "User.Comments")
		(21 "Eco1.User" user "User.Eco1")
		(23 "Eco2.User" user "User.Eco2")
		(25 "Edge.Cuts" user "Board Geometry/Outline")
		(27 "Margin" user)
		(31 "F.CrtYd" user "Package Geometry/Place Bound Top")
		(29 "B.CrtYd" user "Package Geometry/Place Bound Bottom")
		(35 "F.Fab" user "Ref Des/Assembly Top")
		(33 "B.Fab" user "Ref Des/Assembly Bottom")
	)
	(footprint ""
		(layer "F.Cu")
		(at 59.649868 -295.89984)
		(property "Reference" "PEX0"
			(at -3.360166 35.566858 0)
			(unlocked yes)
			(layer "F.SilkS")
			(effects
				(font
					(size 2.032 1.524)
					(thickness 0.1524)
				)
				(justify left)
			)
		)
		(property "Value" ""
			(at 0 0 0)
			(layer "F.Fab")
			(effects
				(font
					(size 1.27 1.27)
				)
			)
		)
		(duplicate_pad_numbers_are_jumpers no)
		(pad "U35" smd circle
			(at 9.500108 -7.599934)
			(size 0.4572 0.4572)
			(layers "F.Cu" "F.Mask" "F.Paste")
			(net "GND")
		)
		(pad "U36" smd circle
			(at 10.450068 -7.599934)
			(size 0.4572 0.4572)
			(layers "F.Cu" "F.Mask" "F.Paste")
			(net "Net_482")
		)
		(pad "U37" smd circle
			(at 11.400028 -7.599934)
			(size 0.4572 0.4572)
			(layers "F.Cu" "F.Mask" "F.Paste")
			(net "GND")
		)
		(pad "U38" smd circle
			(at 12.349988 -7.599934)
			(size 0.4572 0.4572)
			(layers "F.Cu" "F.Mask" "F.Paste")
			(net "Net_2839")
		)
		(pad "U39" smd circle
			(at 13.299948 -7.599934)
			(size 0.4572 0.4572)
			(layers "F.Cu" "F.Mask" "F.Paste")
			(net "Net_2833")
		)
		(pad "U40" smd circle
			(at 14.249908 -7.599934)
			(size 0.4572 0.4572)
			(layers "F.Cu" "F.Mask" "F.Paste")
			(net "GND")
		)
		(pad "U41" smd circle
			(at 15.200122 -7.599934)
			(size 0.4572 0.4572)
			(layers "F.Cu" "F.Mask" "F.Paste")
			(net "GND")
		)
		(pad "U42" smd circle
			(at 16.150082 -7.599934)
			(size 0.4572 0.4572)
			(layers "F.Cu" "F.Mask" "F.Paste")
			(net "GND")
		)
		(pad "U43" smd circle
			(at 17.100042 -7.599934)
			(size 0.4572 0.4572)
			(layers "F.Cu" "F.Mask" "F.Paste")
			(net "Net_2814")
		)
		(pad "U44" smd circle
			(at 18.050002 -7.599934)
			(size 0.4572 0.4572)
			(layers "F.Cu" "F.Mask" "F.Paste")
			(net "Net_2798")
		)
		(pad "U45" smd circle
			(at 18.999962 -7.599934)
			(size 0.4572 0.4572)
			(layers "F.Cu" "F.Mask" "F.Paste")
			(net "GND")
		)
		(pad "U46" smd circle
			(at 19.949922 -7.599934)
			(size 0.4572 0.4572)
			(layers "F.Cu" "F.Mask" "F.Paste")
			(net "Net_2782")
		)
		(pad "U47" smd circle
			(at 20.899882 -7.599934)
			(size 0.4572 0.4572)
			(layers "F.Cu" "F.Mask" "F.Paste")
			(net "Net_2766")
		)
		(pad "U48" smd circle
			(at 21.850096 -7.599934)
			(size 0.4572 0.4572)
			(layers "F.Cu" "F.Mask" "F.Paste")
			(net "GND")
		)
		(pad "U49" smd circle
			(at 22.800056 -7.599934)
			(size 0.4572 0.4572)
			(layers "F.Cu" "F.Mask" "F.Paste")
			(net "GND")
		)
		(pad "V1" smd circle
			(at -22.800056 -6.649974)
			(size 0.4572 0.4572)
			(layers "F.Cu" "F.Mask" "F.Paste")
			(net "P5E_PEX0_STN7_RX_DN<113>")
		)
		(pad "V2" smd circle
			(at -21.850096 -6.649974)
			(size 0.4572 0.4572)
			(layers "F.Cu" "F.Mask" "F.Paste")
			(net "P5E_PEX0_STN7_RX_DP<113>")
		)
		(pad "V3" smd circle
			(at -20.899882 -6.649974)
			(size 0.4572 0.4572)
			(layers "F.Cu" "F.Mask" "F.Paste")
			(net "GND")
		)
		(pad "V4" smd circle
			(at -19.949922 -6.649974)
			(size 0.4572 0.4572)
			(layers "F.Cu" "F.Mask" "F.Paste")
			(net "GND")
		)
		(pad "V5" smd circle
			(at -18.999962 -6.649974)
			(size 0.4572 0.4572)
			(layers "F.Cu" "F.Mask" "F.Paste")
			(net "GND")
		)
		(pad "V6" smd circle
			(at -18.050002 -6.649974)
			(size 0.4572 0.4572)
			(layers "F.Cu" "F.Mask" "F.Paste")
			(net "GND")
		)
		(pad "V7" smd circle
			(at -17.100042 -6.649974)
			(size 0.4572 0.4572)
			(layers "F.Cu" "F.Mask" "F.Paste")
			(net "GND")
		)
		(pad "V8" smd circle
			(at -16.150082 -6.649974)
			(size 0.4572 0.4572)
			(layers "F.Cu" "F.Mask" "F.Paste")
			(net "P5E_PEX0_STN7_TX_DN<113>")
		)
		(pad "V9" smd circle
			(at -15.200122 -6.649974)
			(size 0.4572 0.4572)
			(layers "F.Cu" "F.Mask" "F.Paste")
			(net "P5E_PEX0_STN7_TX_DP<113>")
		)
		(pad "V10" smd circle
			(at -14.249908 -6.649974)
			(size 0.4572 0.4572)
			(layers "F.Cu" "F.Mask" "F.Paste")
			(net "GND")
		)
		(pad "V11" smd circle
			(at -13.299948 -6.649974)
			(size 0.4572 0.4572)
			(layers "F.Cu" "F.Mask" "F.Paste")
			(net "GND")
		)
		(pad "V12" smd circle
			(at -12.349988 -6.649974)
			(size 0.4572 0.4572)
			(layers "F.Cu" "F.Mask" "F.Paste")
			(net "GND")
		)
		(pad "V13" smd circle
			(at -11.400028 -6.649974)
			(size 0.4572 0.4572)
			(layers "F.Cu" "F.Mask" "F.Paste")
			(net "GND")
		)
		(pad "V14" smd circle
			(at -10.450068 -6.649974)
			(size 0.4572 0.4572)
			(layers "F.Cu" "F.Mask" "F.Paste")
			(net "P1V8_VDDA_PEX0")
		)
		(pad "V15" smd circle
			(at -9.500108 -6.649974)
			(size 0.4572 0.4572)
			(layers "F.Cu" "F.Mask" "F.Paste")
			(net "GND")
		)
		(pad "V16" smd circle
			(at -8.549894 -6.649974)
			(size 0.4572 0.4572)
			(layers "F.Cu" "F.Mask" "F.Paste")
			(net "P1V25_PEX0")
		)
		(pad "V17" smd circle
			(at -7.599934 -6.649974)
			(size 0.4572 0.4572)
			(layers "F.Cu" "F.Mask" "F.Paste")
			(net "P1V25_PEX0")
		)
		(pad "V18" smd circle
			(at -6.649974 -6.649974)
			(size 0.4572 0.4572)
			(layers "F.Cu" "F.Mask" "F.Paste")
			(net "P1V25_PEX0")
		)
		(pad "V19" smd circle
			(at -5.700014 -6.649974)
			(size 0.4572 0.4572)
			(layers "F.Cu" "F.Mask" "F.Paste")
			(net "P1V25_PEX0")
		)
		(pad "V20" smd circle
			(at -4.750054 -6.649974)
			(size 0.4572 0.4572)
			(layers "F.Cu" "F.Mask" "F.Paste")
			(net "P1V25_PEX0")
		)
		(pad "V21" smd circle
			(at -3.800094 -6.649974)
			(size 0.4572 0.4572)
			(layers "F.Cu" "F.Mask" "F.Paste")
			(net "P1V25_PEX0")
		)
		(pad "V22" smd circle
			(at -2.84988 -6.649974)
			(size 0.4572 0.4572)
			(layers "F.Cu" "F.Mask" "F.Paste")
			(net "P1V25_PEX0")
		)
		(pad "V23" smd circle
			(at -1.89992 -6.649974)
			(size 0.4572 0.4572)
			(layers "F.Cu" "F.Mask" "F.Paste")
			(net "P1V25_PEX0")
		)
		(pad "V24" smd circle
			(at -0.94996 -6.649974)
			(size 0.4572 0.4572)
			(layers "F.Cu" "F.Mask" "F.Paste")
			(net "P1V25_PEX0")
		)
		(pad "V25" smd circle
			(at 0 -6.649974)
			(size 0.4572 0.4572)
			(layers "F.Cu" "F.Mask" "F.Paste")
			(net "P1V25_PEX0")
		)
		(pad "V26" smd circle
			(at 0.94996 -6.649974)
			(size 0.4572 0.4572)
			(layers "F.Cu" "F.Mask" "F.Paste")
			(net "P1V25_PEX0")
		)
		(pad "V27" smd circle
			(at 1.89992 -6.649974)
			(size 0.4572 0.4572)
			(layers "F.Cu" "F.Mask" "F.Paste")
			(net "P1V25_PEX0")
		)
		(pad "V28" smd circle
			(at 2.84988 -6.649974)
			(size 0.4572 0.4572)
			(layers "F.Cu" "F.Mask" "F.Paste")
			(net "P1V25_PEX0")
		)
		(pad "V29" smd circle
			(at 3.800094 -6.649974)
			(size 0.4572 0.4572)
			(layers "F.Cu" "F.Mask" "F.Paste")
			(net "P1V25_PEX0")
		)
		(pad "V30" smd circle
			(at 4.750054 -6.649974)
			(size 0.4572 0.4572)
			(layers "F.Cu" "F.Mask" "F.Paste")
			(net "P1V25_PEX0")
		)
		(pad "V31" smd circle
			(at 5.700014 -6.649974)
			(size 0.4572 0.4572)
			(layers "F.Cu" "F.Mask" "F.Paste")
			(net "P1V25_PEX0")
		)
		(pad "V32" smd circle
			(at 6.649974 -6.649974)
			(size 0.4572 0.4572)
			(layers "F.Cu" "F.Mask" "F.Paste")
			(net "P1V25_PEX0")
		)
		(pad "V33" smd circle
			(at 7.599934 -6.649974)
			(size 0.4572 0.4572)
			(layers "F.Cu" "F.Mask" "F.Paste")
			(net "P1V25_PEX0")
		)
		(pad "V34" smd circle
			(at 8.549894 -6.649974)
			(size 0.4572 0.4572)
			(layers "F.Cu" "F.Mask" "F.Paste")
			(net "GND")
		)
		(pad "V35" smd circle
			(at 9.500108 -6.649974)
			(size 0.4572 0.4572)
			(layers "F.Cu" "F.Mask" "F.Paste")
			(net "P1V8_PEX")
		)
		(pad "V36" smd circle
			(at 10.450068 -6.649974)
			(size 0.4572 0.4572)
			(layers "F.Cu" "F.Mask" "F.Paste")
			(net "GND")
		)
		(pad "V37" smd circle
			(at 11.400028 -6.649974)
			(size 0.4572 0.4572)
			(layers "F.Cu" "F.Mask" "F.Paste")
			(net "GND")
		)
		(pad "V38" smd circle
			(at 12.349988 -6.649974)
			(size 0.4572 0.4572)
			(layers "F.Cu" "F.Mask" "F.Paste")
			(net "GND")
		)
		(pad "V39" smd circle
			(at 13.299948 -6.649974)
			(size 0.4572 0.4572)
			(layers "F.Cu" "F.Mask" "F.Paste")
			(net "VSENSE_P0V8_PEX0_SKT_VSEN")
		)
		(pad "V40" smd circle
			(at 14.249908 -6.649974)
			(size 0.4572 0.4572)
			(layers "F.Cu" "F.Mask" "F.Paste")
			(net "GND")
		)
		(pad "V41" smd circle
			(at 15.200122 -6.649974)
			(size 0.4572 0.4572)
			(layers "F.Cu" "F.Mask" "F.Paste")
			(net "Net_2815")
		)
		(pad "V42" smd circle
			(at 16.150082 -6.649974)
			(size 0.4572 0.4572)
			(layers "F.Cu" "F.Mask" "F.Paste")
			(net "Net_2799")
		)
		(pad "V43" smd circle
			(at 17.100042 -6.649974)
			(size 0.4572 0.4572)
			(layers "F.Cu" "F.Mask" "F.Paste")
			(net "GND")
		)
		(pad "V44" smd circle
			(at 18.050002 -6.649974)
			(size 0.4572 0.4572)
			(layers "F.Cu" "F.Mask" "F.Paste")
			(net "GND")
		)
		(pad "V45" smd circle
			(at 18.999962 -6.649974)
			(size 0.4572 0.4572)
			(layers "F.Cu" "F.Mask" "F.Paste")
			(net "GND")
		)
		(pad "V46" smd circle
			(at 19.949922 -6.649974)
			(size 0.4572 0.4572)
			(layers "F.Cu" "F.Mask" "F.Paste")
			(net "GND")
		)
		(pad "V47" smd circle
			(at 20.899882 -6.649974)
			(size 0.4572 0.4572)
			(layers "F.Cu" "F.Mask" "F.Paste")
			(net "GND")
		)
		(pad "V48" smd circle
			(at 21.850096 -6.649974)
			(size 0.4572 0.4572)
			(layers "F.Cu" "F.Mask" "F.Paste")
			(net "Net_2783")
		)
		(pad "V49" smd circle
			(at 22.800056 -6.649974)
			(size 0.4572 0.4572)
			(layers "F.Cu" "F.Mask" "F.Paste")
			(net "Net_2767")
		)
		(pad "W1" smd circle
			(at -22.800056 -5.700014)
			(size 0.4572 0.4572)
			(layers "F.Cu" "F.Mask" "F.Paste")
			(net "GND")
		)
		(pad "W2" smd circle
			(at -21.850096 -5.700014)
			(size 0.4572 0.4572)
			(layers "F.Cu" "F.Mask" "F.Paste")
			(net "GND")
		)
		(pad "W3" smd circle
			(at -20.899882 -5.700014)
			(size 0.4572 0.4572)
			(layers "F.Cu" "F.Mask" "F.Paste")
			(net "P5E_PEX0_STN7_RX_DN<112>")
		)
		(pad "W4" smd circle
			(at -19.949922 -5.700014)
			(size 0.4572 0.4572)
			(layers "F.Cu" "F.Mask" "F.Paste")
			(net "P5E_PEX0_STN7_RX_DP<112>")
		)
		(pad "W5" smd circle
			(at -18.999962 -5.700014)
			(size 0.4572 0.4572)
			(layers "F.Cu" "F.Mask" "F.Paste")
			(net "GND")
		)
		(pad "W6" smd circle
			(at -18.050002 -5.700014)
			(size 0.4572 0.4572)
			(layers "F.Cu" "F.Mask" "F.Paste")
			(net "P5E_PEX0_STN7_TX_DN<112>")
		)
		(pad "W7" smd circle
			(at -17.100042 -5.700014)
			(size 0.4572 0.4572)
			(layers "F.Cu" "F.Mask" "F.Paste")
			(net "P5E_PEX0_STN7_TX_DP<112>")
		)
		(pad "W8" smd circle
			(at -16.150082 -5.700014)
			(size 0.4572 0.4572)
			(layers "F.Cu" "F.Mask" "F.Paste")
			(net "GND")
		)
		(pad "W9" smd circle
			(at -15.200122 -5.700014)
			(size 0.4572 0.4572)
			(layers "F.Cu" "F.Mask" "F.Paste")
			(net "GND")
		)
		(pad "W10" smd circle
			(at -14.249908 -5.700014)
			(size 0.4572 0.4572)
			(layers "F.Cu" "F.Mask" "F.Paste")
			(net "GND")
		)
		(pad "W11" smd circle
			(at -13.299948 -5.700014)
			(size 0.4572 0.4572)
			(layers "F.Cu" "F.Mask" "F.Paste")
			(net "GND")
		)
		(pad "W12" smd circle
			(at -12.349988 -5.700014)
			(size 0.4572 0.4572)
			(layers "F.Cu" "F.Mask" "F.Paste")
			(net "GND")
		)
		(pad "W13" smd circle
			(at -11.400028 -5.700014)
			(size 0.4572 0.4572)
			(layers "F.Cu" "F.Mask" "F.Paste")
			(net "GND")
		)
		(pad "W14" smd circle
			(at -10.450068 -5.700014)
			(size 0.4572 0.4572)
			(layers "F.Cu" "F.Mask" "F.Paste")
			(net "GND")
		)
		(pad "W15" smd circle
			(at -9.500108 -5.700014)
			(size 0.4572 0.4572)
			(layers "F.Cu" "F.Mask" "F.Paste")
			(net "GND")
		)
		(pad "W16" smd circle
			(at -8.549894 -5.700014)
			(size 0.4572 0.4572)
			(layers "F.Cu" "F.Mask" "F.Paste")
			(net "GND")
		)
		(pad "W17" smd circle
			(at -7.599934 -5.700014)
			(size 0.4572 0.4572)
			(layers "F.Cu" "F.Mask" "F.Paste")
			(net "GND")
		)
		(pad "W18" smd circle
			(at -6.649974 -5.700014)
			(size 0.4572 0.4572)
			(layers "F.Cu" "F.Mask" "F.Paste")
			(net "GND")
		)
		(pad "W19" smd circle
			(at -5.700014 -5.700014)
			(size 0.4572 0.4572)
			(layers "F.Cu" "F.Mask" "F.Paste")
			(net "GND")
		)
		(pad "W20" smd circle
			(at -4.750054 -5.700014)
			(size 0.4572 0.4572)
			(layers "F.Cu" "F.Mask" "F.Paste")
			(net "GND")
		)
		(pad "W21" smd circle
			(at -3.800094 -5.700014)
			(size 0.4572 0.4572)
			(layers "F.Cu" "F.Mask" "F.Paste")
			(net "GND")
		)
		(pad "W22" smd circle
			(at -2.84988 -5.700014)
			(size 0.4572 0.4572)
			(layers "F.Cu" "F.Mask" "F.Paste")
			(net "GND")
		)
		(pad "W23" smd circle
			(at -1.89992 -5.700014)
			(size 0.4572 0.4572)
			(layers "F.Cu" "F.Mask" "F.Paste")
			(net "GND")
		)
		(pad "W24" smd circle
			(at -0.94996 -5.700014)
			(size 0.4572 0.4572)
			(layers "F.Cu" "F.Mask" "F.Paste")
			(net "GND")
		)
		(pad "W25" smd circle
			(at 0 -5.700014)
			(size 0.4572 0.4572)
			(layers "F.Cu" "F.Mask" "F.Paste")
			(net "GND")
		)
		(pad "W26" smd circle
			(at 0.94996 -5.700014)
			(size 0.4572 0.4572)
			(layers "F.Cu" "F.Mask" "F.Paste")
			(net "GND")
		)
		(pad "W27" smd circle
			(at 1.89992 -5.700014)
			(size 0.4572 0.4572)
			(layers "F.Cu" "F.Mask" "F.Paste")
			(net "GND")
		)
		(pad "W28" smd circle
			(at 2.84988 -5.700014)
			(size 0.4572 0.4572)
			(layers "F.Cu" "F.Mask" "F.Paste")
			(net "GND")
		)
		(pad "W29" smd circle
			(at 3.800094 -5.700014)
			(size 0.4572 0.4572)
			(layers "F.Cu" "F.Mask" "F.Paste")
			(net "GND")
		)
		(pad "W30" smd circle
			(at 4.750054 -5.700014)
			(size 0.4572 0.4572)
			(layers "F.Cu" "F.Mask" "F.Paste")
			(net "GND")
		)
		(pad "W31" smd circle
			(at 5.700014 -5.700014)
			(size 0.4572 0.4572)
			(layers "F.Cu" "F.Mask" "F.Paste")
			(net "GND")
		)
		(pad "W32" smd circle
			(at 6.649974 -5.700014)
			(size 0.4572 0.4572)
			(layers "F.Cu" "F.Mask" "F.Paste")
			(net "GND")
		)
		(pad "W33" smd circle
			(at 7.599934 -5.700014)
			(size 0.4572 0.4572)
			(layers "F.Cu" "F.Mask" "F.Paste")
			(net "GND")
		)
		(pad "W34" smd circle
			(at 8.549894 -5.700014)
			(size 0.4572 0.4572)
			(layers "F.Cu" "F.Mask" "F.Paste")
			(net "GND")
		)
		(pad "W35" smd circle
			(at 9.500108 -5.700014)
			(size 0.4572 0.4572)
			(layers "F.Cu" "F.Mask" "F.Paste")
			(net "P1V8_PEX")
		)
		(pad "W36" smd circle
			(at 10.450068 -5.700014)
			(size 0.4572 0.4572)
			(layers "F.Cu" "F.Mask" "F.Paste")
			(net "GND")
		)
		(pad "W37" smd circle
			(at 11.400028 -5.700014)
			(size 0.4572 0.4572)
			(layers "F.Cu" "F.Mask" "F.Paste")
			(net "GND")
		)
		(pad "W38" smd circle
			(at 12.349988 -5.700014)
			(size 0.4572 0.4572)
			(layers "F.Cu" "F.Mask" "F.Paste")
			(net "GND")
		)
		(pad "W39" smd circle
			(at 13.299948 -5.700014)
			(size 0.4572 0.4572)
			(layers "F.Cu" "F.Mask" "F.Paste")
			(net "VSENSE_P0V8_PEX0_SKT_VRTN")
		)
		(pad "W40" smd circle
			(at 14.249908 -5.700014)
			(size 0.4572 0.4572)
			(layers "F.Cu" "F.Mask" "F.Paste")
			(net "GND")
		)
		(pad "W41" smd circle
			(at 15.200122 -5.700014)
			(size 0.4572 0.4572)
			(layers "F.Cu" "F.Mask" "F.Paste")
			(net "GND")
		)
		(pad "W42" smd circle
			(at 16.150082 -5.700014)
			(size 0.4572 0.4572)
			(layers "F.Cu" "F.Mask" "F.Paste")
			(net "GND")
		)
		(pad "W43" smd circle
			(at 17.100042 -5.700014)
			(size 0.4572 0.4572)
			(layers "F.Cu" "F.Mask" "F.Paste")
			(net "Net_2816")
		)
		(pad "W44" smd circle
			(at 18.050002 -5.700014)
			(size 0.4572 0.4572)
			(layers "F.Cu" "F.Mask" "F.Paste")
			(net "Net_2800")
		)
		(pad "W45" smd circle
			(at 18.999962 -5.700014)
			(size 0.4572 0.4572)
			(layers "F.Cu" "F.Mask" "F.Paste")
			(net "GND")
		)
		(pad "W46" smd circle
			(at 19.949922 -5.700014)
			(size 0.4572 0.4572)
			(layers "F.Cu" "F.Mask" "F.Paste")
			(net "Net_2784")
		)
		(pad "W47" smd circle
			(at 20.899882 -5.700014)
			(size 0.4572 0.4572)
			(layers "F.Cu" "F.Mask" "F.Paste")
			(net "Net_2768")
		)
		(pad "W48" smd circle
			(at 21.850096 -5.700014)
			(size 0.4572 0.4572)
			(layers "F.Cu" "F.Mask" "F.Paste")
			(net "GND")
		)
		(pad "W49" smd circle
			(at 22.800056 -5.700014)
			(size 0.4572 0.4572)
			(layers "F.Cu" "F.Mask" "F.Paste")
			(net "GND")
		)
		(pad "Y1" smd circle
			(at -22.800056 -4.750054)
			(size 0.4572 0.4572)
			(layers "F.Cu" "F.Mask" "F.Paste")
			(net "GND")
		)
		(pad "Y2" smd circle
			(at -21.850096 -4.750054)
			(size 0.4572 0.4572)
			(layers "F.Cu" "F.Mask" "F.Paste")
			(net "GND")
		)
		(pad "Y3" smd circle
			(at -20.899882 -4.750054)
			(size 0.4572 0.4572)
			(layers "F.Cu" "F.Mask" "F.Paste")
			(net "GND")
		)
		(pad "Y4" smd circle
			(at -19.949922 -4.750054)
			(size 0.4572 0.4572)
			(layers "F.Cu" "F.Mask" "F.Paste")
			(net "GND")
		)
		(pad "Y5" smd circle
			(at -18.999962 -4.750054)
			(size 0.4572 0.4572)
			(layers "F.Cu" "F.Mask" "F.Paste")
			(net "GND")
		)
		(pad "Y6" smd circle
			(at -18.050002 -4.750054)
			(size 0.4572 0.4572)
			(layers "F.Cu" "F.Mask" "F.Paste")
			(net "GND")
		)
		(pad "Y7" smd circle
			(at -17.100042 -4.750054)
			(size 0.4572 0.4572)
			(layers "F.Cu" "F.Mask" "F.Paste")
			(net "GND")
		)
		(pad "Y8" smd circle
			(at -16.150082 -4.750054)
			(size 0.4572 0.4572)
			(layers "F.Cu" "F.Mask" "F.Paste")
			(net "GND")
		)
	)
)
